(kicad_pcb
	(version 20260206)
	(generator "pcbnew")
	(generator_version "10.0")
	(general
		(thickness 1.6)
		(legacy_teardrops no)
	)
	(paper "A4")
	(title_block
		(title "03242023_DA0F0TMBIJ0_F0T_Motherboard_J_brd_V01_OCP.brd")
		(comment 1 "Grand Teton / footprints 4178-4183 of 6105")
	)
	(layers
		(0 "F.Cu" signal "TOP")
		(4 "In1.Cu" signal "GND")
		(6 "In2.Cu" signal "IN1")
		(8 "In3.Cu" signal "GND1")
		(10 "In4.Cu" signal "IN2")
		(12 "In5.Cu" signal "GND2")
		(14 "In6.Cu" signal "IN3")
		(16 "In7.Cu" signal "GND3")
		(18 "In8.Cu" signal "VCC")
		(20 "In9.Cu" signal "VCC1")
		(22 "In10.Cu" signal "GND4")
		(24 "In11.Cu" signal "IN4")
		(26 "In12.Cu" signal "GND5")
		(28 "In13.Cu" signal "IN5")
		(30 "In14.Cu" signal "GND6")
		(32 "In15.Cu" signal "IN6")
		(34 "In16.Cu" signal "GND7")
		(2 "B.Cu" signal "BOTTOM")
		(9 "F.Adhes" user "F.Adhesive")
		(11 "B.Adhes" user "B.Adhesive")
		(13 "F.Paste" user "Package Geometry/Pastemask Top")
		(15 "B.Paste" user "Package Geometry/Pastemask Bottom")
		(5 "F.SilkS" user "Ref Des/Silkscreen Top")
		(7 "B.SilkS" user "Ref Des/Silkscreen Bottom")
		(1 "F.Mask" user "Board Geometry/Soldermask Top")
		(3 "B.Mask" user "Board Geometry/Soldermask Bottom")
		(17 "Dwgs.User" user "User.Drawings")
		(19 "Cmts.User" user "User.Comments")
		(21 "Eco1.User" user "User.Eco1")
		(23 "Eco2.User" user "User.Eco2")
		(25 "Edge.Cuts" user "Board Geometry/Outline")
		(27 "Margin" user)
		(31 "F.CrtYd" user "Package Geometry/Place Bound Top")
		(29 "B.CrtYd" user "Package Geometry/Place Bound Bottom")
		(35 "F.Fab" user "Ref Des/Assembly Top")
		(33 "B.Fab" user "Ref Des/Assembly Bottom")
	)
	(footprint ""
		(layer "B.Cu")
		(at 29.577538 -165.540436)
		(property "Reference" "PR214"
			(at 0 0 0)
			(layer "B.SilkS")
			(hide yes)
			(effects
				(font
					(size 1.27 1.27)
				)
				(justify mirror)
			)
		)
		(property "Value" ""
			(at 0 0 0)
			(layer "B.Fab")
			(effects
				(font
					(size 1.27 1.27)
				)
				(justify mirror)
			)
		)
		(duplicate_pad_numbers_are_jumpers no)
		(fp_line
			(start -0.7874 -0.4064)
			(end -0.7874 0.4064)
			(stroke
				(width 0.1524)
				(type default)
			)
			(layer "B.SilkS")
		)
		(fp_line
			(start -0.7874 0.4064)
			(end 0.7874 0.4064)
			(stroke
				(width 0.1524)
				(type default)
			)
			(layer "B.SilkS")
		)
		(fp_line
			(start 0.7874 -0.4064)
			(end -0.7874 -0.4064)
			(stroke
				(width 0.1524)
				(type default)
			)
			(layer "B.SilkS")
		)
		(fp_line
			(start 0.7874 0.4064)
			(end 0.7874 -0.4064)
			(stroke
				(width 0.1524)
				(type default)
			)
			(layer "B.SilkS")
		)
		(fp_line
			(start -0.67945 -0.3048)
			(end -0.67945 0.3048)
			(stroke
				(width 0.1)
				(type default)
			)
			(layer "B.Fab")
		)
		(fp_line
			(start -0.67945 0.3048)
			(end -0.120396 0.3048)
			(stroke
				(width 0.1)
				(type default)
			)
			(layer "B.Fab")
		)
		(fp_line
			(start -0.12065 -0.3048)
			(end -0.67945 -0.3048)
			(stroke
				(width 0.1)
				(type default)
			)
			(layer "B.Fab")
		)
		(fp_line
			(start -0.12065 -0.2794)
			(end -0.12065 -0.3048)
			(stroke
				(width 0.1)
				(type default)
			)
			(layer "B.Fab")
		)
		(fp_line
			(start -0.120396 0.2794)
			(end 0.12065 0.2794)
			(stroke
				(width 0.1)
				(type default)
			)
			(layer "B.Fab")
		)
		(fp_line
			(start -0.120396 0.3048)
			(end -0.120396 0.2794)
			(stroke
				(width 0.1)
				(type default)
			)
			(layer "B.Fab")
		)
		(fp_line
			(start 0.12065 -0.305054)
			(end 0.12065 -0.2794)
			(stroke
				(width 0.1)
				(type default)
			)
			(layer "B.Fab")
		)
		(fp_line
			(start 0.12065 -0.2794)
			(end -0.12065 -0.2794)
			(stroke
				(width 0.1)
				(type default)
			)
			(layer "B.Fab")
		)
		(fp_line
			(start 0.12065 0.2794)
			(end 0.12065 0.3048)
			(stroke
				(width 0.1)
				(type default)
			)
			(layer "B.Fab")
		)
		(fp_line
			(start 0.12065 0.3048)
			(end 0.67945 0.3048)
			(stroke
				(width 0.1)
				(type default)
			)
			(layer "B.Fab")
		)
		(fp_line
			(start 0.67945 -0.305054)
			(end 0.12065 -0.305054)
			(stroke
				(width 0.1)
				(type default)
			)
			(layer "B.Fab")
		)
		(fp_line
			(start 0.67945 0.3048)
			(end 0.67945 -0.305054)
			(stroke
				(width 0.1)
				(type default)
			)
			(layer "B.Fab")
		)
		(pad "1" smd circle
			(at 0.40005 0 180)
			(size 0 0)
			(layers "B.Cu" "B.Mask" "B.Paste")
			(net "PVCCD_HV_CPU1_ISENSE_P")
		)
		(pad "2" smd circle
			(at -0.40005 0 180)
			(size 0 0)
			(layers "B.Cu" "B.Mask" "B.Paste")
			(net "GND")
		)
	)
	(footprint ""
		(layer "B.Cu")
		(at 174.235872 -13.762228 -90)
		(property "Reference" "R1460"
			(at 0 0 90)
			(layer "B.SilkS")
			(hide yes)
			(effects
				(font
					(size 1.27 1.27)
				)
				(justify mirror)
			)
		)
		(property "Value" ""
			(at 0 0 90)
			(layer "B.Fab")
			(effects
				(font
					(size 1.27 1.27)
				)
				(justify mirror)
			)
		)
		(duplicate_pad_numbers_are_jumpers no)
		(fp_line
			(start -0.7874 0.4064)
			(end 0.7874 0.4064)
			(stroke
				(width 0.1524)
				(type default)
			)
			(layer "B.SilkS")
		)
		(fp_line
			(start 0.7874 0.4064)
			(end 0.7874 -0.4064)
			(stroke
				(width 0.1524)
				(type default)
			)
			(layer "B.SilkS")
		)
		(fp_line
			(start -0.7874 -0.4064)
			(end -0.7874 0.4064)
			(stroke
				(width 0.1524)
				(type default)
			)
			(layer "B.SilkS")
		)
		(fp_line
			(start 0.7874 -0.4064)
			(end -0.7874 -0.4064)
			(stroke
				(width 0.1524)
				(type default)
			)
			(layer "B.SilkS")
		)
		(fp_line
			(start -0.67945 0.3048)
			(end -0.120396 0.3048)
			(stroke
				(width 0.1)
				(type default)
			)
			(layer "B.Fab")
		)
		(fp_line
			(start -0.120396 0.3048)
			(end -0.120396 0.2794)
			(stroke
				(width 0.1)
				(type default)
			)
			(layer "B.Fab")
		)
		(fp_line
			(start 0.12065 0.3048)
			(end 0.67945 0.3048)
			(stroke
				(width 0.1)
				(type default)
			)
			(layer "B.Fab")
		)
		(fp_line
			(start 0.67945 0.3048)
			(end 0.67945 -0.305054)
			(stroke
				(width 0.1)
				(type default)
			)
			(layer "B.Fab")
		)
		(fp_line
			(start -0.120396 0.2794)
			(end 0.12065 0.2794)
			(stroke
				(width 0.1)
				(type default)
			)
			(layer "B.Fab")
		)
		(fp_line
			(start 0.12065 0.2794)
			(end 0.12065 0.3048)
			(stroke
				(width 0.1)
				(type default)
			)
			(layer "B.Fab")
		)
		(fp_line
			(start -0.12065 -0.2794)
			(end -0.12065 -0.3048)
			(stroke
				(width 0.1)
				(type default)
			)
			(layer "B.Fab")
		)
		(fp_line
			(start 0.12065 -0.2794)
			(end -0.12065 -0.2794)
			(stroke
				(width 0.1)
				(type default)
			)
			(layer "B.Fab")
		)
		(fp_line
			(start -0.67945 -0.3048)
			(end -0.67945 0.3048)
			(stroke
				(width 0.1)
				(type default)
			)
			(layer "B.Fab")
		)
		(fp_line
			(start -0.12065 -0.3048)
			(end -0.67945 -0.3048)
			(stroke
				(width 0.1)
				(type default)
			)
			(layer "B.Fab")
		)
		(fp_line
			(start 0.12065 -0.305054)
			(end 0.12065 -0.2794)
			(stroke
				(width 0.1)
				(type default)
			)
			(layer "B.Fab")
		)
		(fp_line
			(start 0.67945 -0.305054)
			(end 0.12065 -0.305054)
			(stroke
				(width 0.1)
				(type default)
			)
			(layer "B.Fab")
		)
		(pad "1" smd circle
			(at 0.40005 0 90)
			(size 0 0)
			(layers "B.Cu" "B.Mask" "B.Paste")
			(net "I3C_BMC_SWB_SDA")
		)
		(pad "2" smd circle
			(at -0.40005 0 90)
			(size 0 0)
			(layers "B.Cu" "B.Mask" "B.Paste")
			(net "P3V3_AUX")
		)
	)
	(footprint ""
		(layer "B.Cu")
		(at 412.007558 -365.383064 -90)
		(property "Reference" "PR1322"
			(at 0 0 90)
			(layer "B.SilkS")
			(hide yes)
			(effects
				(font
					(size 1.27 1.27)
				)
				(justify mirror)
			)
		)
		(property "Value" ""
			(at 0 0 90)
			(layer "B.Fab")
			(effects
				(font
					(size 1.27 1.27)
				)
				(justify mirror)
			)
		)
		(duplicate_pad_numbers_are_jumpers no)
		(fp_line
			(start -0.7874 0.4064)
			(end 0.7874 0.4064)
			(stroke
				(width 0.1524)
				(type default)
			)
			(layer "B.SilkS")
		)
		(fp_line
			(start 0.7874 0.4064)
			(end 0.7874 -0.4064)
			(stroke
				(width 0.1524)
				(type default)
			)
			(layer "B.SilkS")
		)
		(fp_line
			(start -0.7874 -0.4064)
			(end -0.7874 0.4064)
			(stroke
				(width 0.1524)
				(type default)
			)
			(layer "B.SilkS")
		)
		(fp_line
			(start 0.7874 -0.4064)
			(end -0.7874 -0.4064)
			(stroke
				(width 0.1524)
				(type default)
			)
			(layer "B.SilkS")
		)
		(fp_line
			(start -0.67945 0.3048)
			(end -0.120396 0.3048)
			(stroke
				(width 0.1)
				(type default)
			)
			(layer "B.Fab")
		)
		(fp_line
			(start -0.120396 0.3048)
			(end -0.120396 0.2794)
			(stroke
				(width 0.1)
				(type default)
			)
			(layer "B.Fab")
		)
		(fp_line
			(start 0.12065 0.3048)
			(end 0.67945 0.3048)
			(stroke
				(width 0.1)
				(type default)
			)
			(layer "B.Fab")
		)
		(fp_line
			(start 0.67945 0.3048)
			(end 0.67945 -0.305054)
			(stroke
				(width 0.1)
				(type default)
			)
			(layer "B.Fab")
		)
		(fp_line
			(start -0.120396 0.2794)
			(end 0.12065 0.2794)
			(stroke
				(width 0.1)
				(type default)
			)
			(layer "B.Fab")
		)
		(fp_line
			(start 0.12065 0.2794)
			(end 0.12065 0.3048)
			(stroke
				(width 0.1)
				(type default)
			)
			(layer "B.Fab")
		)
		(fp_line
			(start -0.12065 -0.2794)
			(end -0.12065 -0.3048)
			(stroke
				(width 0.1)
				(type default)
			)
			(layer "B.Fab")
		)
		(fp_line
			(start 0.12065 -0.2794)
			(end -0.12065 -0.2794)
			(stroke
				(width 0.1)
				(type default)
			)
			(layer "B.Fab")
		)
		(fp_line
			(start -0.67945 -0.3048)
			(end -0.67945 0.3048)
			(stroke
				(width 0.1)
				(type default)
			)
			(layer "B.Fab")
		)
		(fp_line
			(start -0.12065 -0.3048)
			(end -0.67945 -0.3048)
			(stroke
				(width 0.1)
				(type default)
			)
			(layer "B.Fab")
		)
		(fp_line
			(start 0.12065 -0.305054)
			(end 0.12065 -0.2794)
			(stroke
				(width 0.1)
				(type default)
			)
			(layer "B.Fab")
		)
		(fp_line
			(start 0.67945 -0.305054)
			(end 0.12065 -0.305054)
			(stroke
				(width 0.1)
				(type default)
			)
			(layer "B.Fab")
		)
		(pad "1" smd circle
			(at 0.40005 0 90)
			(size 0 0)
			(layers "B.Cu" "B.Mask" "B.Paste")
			(net "PVCCFA_EHV_FIVRA_CPU0_VOS1")
		)
		(pad "2" smd circle
			(at -0.40005 0 90)
			(size 0 0)
			(layers "B.Cu" "B.Mask" "B.Paste")
			(net "PVCCFA_EHV_FIVRA_CPU0")
		)
	)
	(footprint ""
		(layer "B.Cu")
		(at 21.914612 -167.548814 180)
		(property "Reference" "R2577"
			(at 0 0 0)
			(layer "B.SilkS")
			(hide yes)
			(effects
				(font
					(size 1.27 1.27)
				)
				(justify mirror)
			)
		)
		(property "Value" ""
			(at 0 0 0)
			(layer "B.Fab")
			(effects
				(font
					(size 1.27 1.27)
				)
				(justify mirror)
			)
		)
		(duplicate_pad_numbers_are_jumpers no)
		(fp_line
			(start 0.7874 0.4064)
			(end 0.7874 -0.4064)
			(stroke
				(width 0.1524)
				(type default)
			)
			(layer "B.SilkS")
		)
		(fp_line
			(start 0.7874 -0.4064)
			(end -0.7874 -0.4064)
			(stroke
				(width 0.1524)
				(type default)
			)
			(layer "B.SilkS")
		)
		(fp_line
			(start -0.7874 0.4064)
			(end 0.7874 0.4064)
			(stroke
				(width 0.1524)
				(type default)
			)
			(layer "B.SilkS")
		)
		(fp_line
			(start -0.7874 -0.4064)
			(end -0.7874 0.4064)
			(stroke
				(width 0.1524)
				(type default)
			)
			(layer "B.SilkS")
		)
		(fp_line
			(start 0.67945 0.3048)
			(end 0.67945 -0.305054)
			(stroke
				(width 0.1)
				(type default)
			)
			(layer "B.Fab")
		)
		(fp_line
			(start 0.67945 -0.305054)
			(end 0.12065 -0.305054)
			(stroke
				(width 0.1)
				(type default)
			)
			(layer "B.Fab")
		)
		(fp_line
			(start 0.12065 0.3048)
			(end 0.67945 0.3048)
			(stroke
				(width 0.1)
				(type default)
			)
			(layer "B.Fab")
		)
		(fp_line
			(start 0.12065 0.2794)
			(end 0.12065 0.3048)
			(stroke
				(width 0.1)
				(type default)
			)
			(layer "B.Fab")
		)
		(fp_line
			(start 0.12065 -0.2794)
			(end -0.12065 -0.2794)
			(stroke
				(width 0.1)
				(type default)
			)
			(layer "B.Fab")
		)
		(fp_line
			(start 0.12065 -0.305054)
			(end 0.12065 -0.2794)
			(stroke
				(width 0.1)
				(type default)
			)
			(layer "B.Fab")
		)
		(fp_line
			(start -0.120396 0.3048)
			(end -0.120396 0.2794)
			(stroke
				(width 0.1)
				(type default)
			)
			(layer "B.Fab")
		)
		(fp_line
			(start -0.120396 0.2794)
			(end 0.12065 0.2794)
			(stroke
				(width 0.1)
				(type default)
			)
			(layer "B.Fab")
		)
		(fp_line
			(start -0.12065 -0.2794)
			(end -0.12065 -0.3048)
			(stroke
				(width 0.1)
				(type default)
			)
			(layer "B.Fab")
		)
		(fp_line
			(start -0.12065 -0.3048)
			(end -0.67945 -0.3048)
			(stroke
				(width 0.1)
				(type default)
			)
			(layer "B.Fab")
		)
		(fp_line
			(start -0.67945 0.3048)
			(end -0.120396 0.3048)
			(stroke
				(width 0.1)
				(type default)
			)
			(layer "B.Fab")
		)
		(fp_line
			(start -0.67945 -0.3048)
			(end -0.67945 0.3048)
			(stroke
				(width 0.1)
				(type default)
			)
			(layer "B.Fab")
		)
		(pad "1" smd circle
			(at 0.40005 0)
			(size 0 0)
			(layers "B.Cu" "B.Mask" "B.Paste")
			(net "FM_PVCCD_HV_CPU1_EN")
		)
		(pad "2" smd circle
			(at -0.40005 0)
			(size 0 0)
			(layers "B.Cu" "B.Mask" "B.Paste")
			(net "PVCCD_HV_CPU1_EN_R")
		)
	)
	(footprint ""
		(layer "B.Cu")
		(at 251.007626 -105.256584 90)
		(property "Reference" "R1680"
			(at 0 0 90)
			(layer "B.SilkS")
			(hide yes)
			(effects
				(font
					(size 1.27 1.27)
				)
				(justify mirror)
			)
		)
		(property "Value" ""
			(at 0 0 90)
			(layer "B.Fab")
			(effects
				(font
					(size 1.27 1.27)
				)
				(justify mirror)
			)
		)
		(duplicate_pad_numbers_are_jumpers no)
		(fp_line
			(start 0.7874 -0.4064)
			(end -0.7874 -0.4064)
			(stroke
				(width 0.1524)
				(type default)
			)
			(layer "B.SilkS")
		)
		(fp_line
			(start -0.7874 -0.4064)
			(end -0.7874 0.4064)
			(stroke
				(width 0.1524)
				(type default)
			)
			(layer "B.SilkS")
		)
		(fp_line
			(start 0.7874 0.4064)
			(end 0.7874 -0.4064)
			(stroke
				(width 0.1524)
				(type default)
			)
			(layer "B.SilkS")
		)
		(fp_line
			(start -0.7874 0.4064)
			(end 0.7874 0.4064)
			(stroke
				(width 0.1524)
				(type default)
			)
			(layer "B.SilkS")
		)
		(fp_line
			(start 0.67945 -0.305054)
			(end 0.12065 -0.305054)
			(stroke
				(width 0.1)
				(type default)
			)
			(layer "B.Fab")
		)
		(fp_line
			(start 0.12065 -0.305054)
			(end 0.12065 -0.2794)
			(stroke
				(width 0.1)
				(type default)
			)
			(layer "B.Fab")
		)
		(fp_line
			(start -0.12065 -0.3048)
			(end -0.67945 -0.3048)
			(stroke
				(width 0.1)
				(type default)
			)
			(layer "B.Fab")
		)
		(fp_line
			(start -0.67945 -0.3048)
			(end -0.67945 0.3048)
			(stroke
				(width 0.1)
				(type default)
			)
			(layer "B.Fab")
		)
		(fp_line
			(start 0.12065 -0.2794)
			(end -0.12065 -0.2794)
			(stroke
				(width 0.1)
				(type default)
			)
			(layer "B.Fab")
		)
		(fp_line
			(start -0.12065 -0.2794)
			(end -0.12065 -0.3048)
			(stroke
				(width 0.1)
				(type default)
			)
			(layer "B.Fab")
		)
		(fp_line
			(start 0.12065 0.2794)
			(end 0.12065 0.3048)
			(stroke
				(width 0.1)
				(type default)
			)
			(layer "B.Fab")
		)
		(fp_line
			(start -0.120396 0.2794)
			(end 0.12065 0.2794)
			(stroke
				(width 0.1)
				(type default)
			)
			(layer "B.Fab")
		)
		(fp_line
			(start 0.67945 0.3048)
			(end 0.67945 -0.305054)
			(stroke
				(width 0.1)
				(type default)
			)
			(layer "B.Fab")
		)
		(fp_line
			(start 0.12065 0.3048)
			(end 0.67945 0.3048)
			(stroke
				(width 0.1)
				(type default)
			)
			(layer "B.Fab")
		)
		(fp_line
			(start -0.120396 0.3048)
			(end -0.120396 0.2794)
			(stroke
				(width 0.1)
				(type default)
			)
			(layer "B.Fab")
		)
		(fp_line
			(start -0.67945 0.3048)
			(end -0.120396 0.3048)
			(stroke
				(width 0.1)
				(type default)
			)
			(layer "B.Fab")
		)
		(pad "1" smd circle
			(at 0.40005 0 270)
			(size 0 0)
			(layers "B.Cu" "B.Mask" "B.Paste")
			(net "FM_PLD_CLK_25M_EN")
		)
		(pad "2" smd circle
			(at -0.40005 0 270)
			(size 0 0)
			(layers "B.Cu" "B.Mask" "B.Paste")
			(net "FM_CK440Q_DEV_25M_EN")
		)
	)
	(footprint ""
		(layer "B.Cu")
		(at 189.039754 -319.450974 180)
		(property "Reference" "C78"
			(at 0 0 0)
			(layer "B.SilkS")
			(hide yes)
			(effects
				(font
					(size 1.27 1.27)
				)
				(justify mirror)
			)
		)
		(property "Value" ""
			(at 0 0 0)
			(layer "B.Fab")
			(effects
				(font
					(size 1.27 1.27)
				)
				(justify mirror)
			)
		)
		(duplicate_pad_numbers_are_jumpers no)
		(fp_line
			(start 0.7874 0.4064)
			(end 0.7874 -0.4064)
			(stroke
				(width 0.1524)
				(type default)
			)
			(layer "B.SilkS")
		)
		(fp_line
			(start 0.7874 -0.4064)
			(end -0.7874 -0.4064)
			(stroke
				(width 0.1524)
				(type default)
			)
			(layer "B.SilkS")
		)
		(fp_line
			(start -0.7874 0.4064)
			(end 0.7874 0.4064)
			(stroke
				(width 0.1524)
				(type default)
			)
			(layer "B.SilkS")
		)
		(fp_line
			(start -0.7874 -0.4064)
			(end -0.7874 0.4064)
			(stroke
				(width 0.1524)
				(type default)
			)
			(layer "B.SilkS")
		)
		(fp_line
			(start 0.67945 0.3048)
			(end 0.67945 -0.305054)
			(stroke
				(width 0.1)
				(type default)
			)
			(layer "B.Fab")
		)
		(fp_line
			(start 0.67945 -0.305054)
			(end 0.12065 -0.305054)
			(stroke
				(width 0.1)
				(type default)
			)
			(layer "B.Fab")
		)
		(fp_line
			(start 0.12065 0.3048)
			(end 0.67945 0.3048)
			(stroke
				(width 0.1)
				(type default)
			)
			(layer "B.Fab")
		)
		(fp_line
			(start 0.12065 0.2794)
			(end 0.12065 0.3048)
			(stroke
				(width 0.1)
				(type default)
			)
			(layer "B.Fab")
		)
		(fp_line
			(start 0.12065 -0.2794)
			(end -0.12065 -0.2794)
			(stroke
				(width 0.1)
				(type default)
			)
			(layer "B.Fab")
		)
		(fp_line
			(start 0.12065 -0.305054)
			(end 0.12065 -0.2794)
			(stroke
				(width 0.1)
				(type default)
			)
			(layer "B.Fab")
		)
		(fp_line
			(start -0.120396 0.3048)
			(end -0.120396 0.2794)
			(stroke
				(width 0.1)
				(type default)
			)
			(layer "B.Fab")
		)
		(fp_line
			(start -0.120396 0.2794)
			(end 0.12065 0.2794)
			(stroke
				(width 0.1)
				(type default)
			)
			(layer "B.Fab")
		)
		(fp_line
			(start -0.12065 -0.2794)
			(end -0.12065 -0.3048)
			(stroke
				(width 0.1)
				(type default)
			)
			(layer "B.Fab")
		)
		(fp_line
			(start -0.12065 -0.3048)
			(end -0.67945 -0.3048)
			(stroke
				(width 0.1)
				(type default)
			)
			(layer "B.Fab")
		)
		(fp_line
			(start -0.67945 0.3048)
			(end -0.120396 0.3048)
			(stroke
				(width 0.1)
				(type default)
			)
			(layer "B.Fab")
		)
		(fp_line
			(start -0.67945 -0.3048)
			(end -0.67945 0.3048)
			(stroke
				(width 0.1)
				(type default)
			)
			(layer "B.Fab")
		)
		(pad "1" smd circle
			(at 0.40005 0)
			(size 0 0)
			(layers "B.Cu" "B.Mask" "B.Paste")
			(net "P3V3_AUX")
		)
		(pad "2" smd circle
			(at -0.40005 0)
			(size 0 0)
			(layers "B.Cu" "B.Mask" "B.Paste")
			(net "GND")
		)
	)
)
